(kicad_pcb
	(version 20260206)
	(generator "pcbnew")
	(generator_version "10.0")
	(general
		(thickness 1.6)
		(legacy_teardrops no)
	)
	(paper "A4")
	(title_block
		(title "04192023_DAF0TMB3IC0_F0TG_MB_C_brd_V02_OCP.brd")
		(comment 1 "Grand Teton / footprints 1766-1771 of 8354")
	)
	(layers
		(0 "F.Cu" signal "TOP")
		(4 "In1.Cu" signal "GND")
		(6 "In2.Cu" signal "IN1")
		(8 "In3.Cu" signal "GND1")
		(10 "In4.Cu" signal "IN2")
		(12 "In5.Cu" signal "GND2")
		(14 "In6.Cu" signal "IN3")
		(16 "In7.Cu" signal "GND3")
		(18 "In8.Cu" signal "VCC")
		(20 "In9.Cu" signal "VCC1")
		(22 "In10.Cu" signal "GND4")
		(24 "In11.Cu" signal "IN4")
		(26 "In12.Cu" signal "GND5")
		(28 "In13.Cu" signal "IN5")
		(30 "In14.Cu" signal "GND6")
		(32 "In15.Cu" signal "IN6")
		(34 "In16.Cu" signal "GND7")
		(2 "B.Cu" signal "BOTTOM")
		(9 "F.Adhes" user "F.Adhesive")
		(11 "B.Adhes" user "B.Adhesive")
		(13 "F.Paste" user "Package Geometry/Pastemask Top")
		(15 "B.Paste" user "Package Geometry/Pastemask Bottom")
		(5 "F.SilkS" user "Ref Des/Silkscreen Top")
		(7 "B.SilkS" user "Ref Des/Silkscreen Bottom")
		(1 "F.Mask" user "Board Geometry/Soldermask Top")
		(3 "B.Mask" user "Board Geometry/Soldermask Bottom")
		(17 "Dwgs.User" user "User.Drawings")
		(19 "Cmts.User" user "User.Comments")
		(21 "Eco1.User" user "User.Eco1")
		(23 "Eco2.User" user "User.Eco2")
		(25 "Edge.Cuts" user "Board Geometry/Outline")
		(27 "Margin" user)
		(31 "F.CrtYd" user "Package Geometry/Place Bound Top")
		(29 "B.CrtYd" user "Package Geometry/Place Bound Bottom")
		(35 "F.Fab" user "Ref Des/Assembly Top")
		(33 "B.Fab" user "Ref Des/Assembly Bottom")
	)
	(footprint ""
		(layer "F.Cu")
		(at 192.688972 -22.694392)
		(property "Reference" "PR4012"
			(at 0 0 0)
			(layer "F.SilkS")
			(hide yes)
			(effects
				(font
					(size 1.27 1.27)
				)
			)
		)
		(property "Value" ""
			(at 0 0 0)
			(layer "F.Fab")
			(effects
				(font
					(size 1.27 1.27)
				)
			)
		)
		(duplicate_pad_numbers_are_jumpers no)
		(fp_line
			(start -0.7874 -0.4064)
			(end 0.7874 -0.4064)
			(stroke
				(width 0.1524)
				(type default)
			)
			(layer "F.SilkS")
		)
		(fp_line
			(start -0.7874 0.4064)
			(end -0.7874 -0.4064)
			(stroke
				(width 0.1524)
				(type default)
			)
			(layer "F.SilkS")
		)
		(fp_line
			(start 0.7874 -0.4064)
			(end 0.7874 0.4064)
			(stroke
				(width 0.1524)
				(type default)
			)
			(layer "F.SilkS")
		)
		(fp_line
			(start 0.7874 0.4064)
			(end -0.7874 0.4064)
			(stroke
				(width 0.1524)
				(type default)
			)
			(layer "F.SilkS")
		)
		(fp_line
			(start -0.67945 -0.305054)
			(end -0.12065 -0.305054)
			(stroke
				(width 0.1)
				(type default)
			)
			(layer "F.Fab")
		)
		(fp_line
			(start -0.67945 0.3048)
			(end -0.67945 -0.305054)
			(stroke
				(width 0.1)
				(type default)
			)
			(layer "F.Fab")
		)
		(fp_line
			(start -0.12065 -0.305054)
			(end -0.12065 -0.2794)
			(stroke
				(width 0.1)
				(type default)
			)
			(layer "F.Fab")
		)
		(fp_line
			(start -0.12065 -0.2794)
			(end 0.12065 -0.2794)
			(stroke
				(width 0.1)
				(type default)
			)
			(layer "F.Fab")
		)
		(fp_line
			(start -0.12065 0.2794)
			(end -0.12065 0.3048)
			(stroke
				(width 0.1)
				(type default)
			)
			(layer "F.Fab")
		)
		(fp_line
			(start -0.12065 0.3048)
			(end -0.67945 0.3048)
			(stroke
				(width 0.1)
				(type default)
			)
			(layer "F.Fab")
		)
		(fp_line
			(start 0.120396 0.2794)
			(end -0.12065 0.2794)
			(stroke
				(width 0.1)
				(type default)
			)
			(layer "F.Fab")
		)
		(fp_line
			(start 0.120396 0.3048)
			(end 0.120396 0.2794)
			(stroke
				(width 0.1)
				(type default)
			)
			(layer "F.Fab")
		)
		(fp_line
			(start 0.12065 -0.3048)
			(end 0.67945 -0.3048)
			(stroke
				(width 0.1)
				(type default)
			)
			(layer "F.Fab")
		)
		(fp_line
			(start 0.12065 -0.2794)
			(end 0.12065 -0.3048)
			(stroke
				(width 0.1)
				(type default)
			)
			(layer "F.Fab")
		)
		(fp_line
			(start 0.67945 -0.3048)
			(end 0.67945 0.3048)
			(stroke
				(width 0.1)
				(type default)
			)
			(layer "F.Fab")
		)
		(fp_line
			(start 0.67945 0.3048)
			(end 0.120396 0.3048)
			(stroke
				(width 0.1)
				(type default)
			)
			(layer "F.Fab")
		)
		(pad "1" smd circle
			(at -0.40005 0)
			(size 0 0)
			(layers "F.Cu" "F.Mask" "F.Paste")
			(net "P12V_SCM_PWRGD")
		)
		(pad "2" smd circle
			(at 0.40005 0)
			(size 0 0)
			(layers "F.Cu" "F.Mask" "F.Paste")
			(net "HP_LVC3_SCM_HSC_PWRGD")
		)
	)
	(footprint ""
		(layer "F.Cu")
		(at 123.127516 -54.775608 90)
		(property "Reference" "U146"
			(at 0.67818 -2.174748 90)
			(unlocked yes)
			(layer "F.SilkS")
			(effects
				(font
					(size 0.7874 0.5842)
					(thickness 0.1524)
				)
				(justify left)
			)
		)
		(property "Value" ""
			(at 0 0 90)
			(layer "F.Fab")
			(effects
				(font
					(size 1.27 1.27)
				)
			)
		)
		(duplicate_pad_numbers_are_jumpers no)
		(fp_line
			(start 1.245616 -1.445768)
			(end 1.245616 1.445768)
			(stroke
				(width 0.1524)
				(type default)
			)
			(layer "F.SilkS")
		)
		(fp_line
			(start -1.245616 -1.445768)
			(end 1.245616 -1.445768)
			(stroke
				(width 0.1524)
				(type default)
			)
			(layer "F.SilkS")
		)
		(fp_line
			(start 1.245616 1.445768)
			(end -1.245616 1.445768)
			(stroke
				(width 0.1524)
				(type default)
			)
			(layer "F.SilkS")
		)
		(fp_line
			(start -1.245616 1.445768)
			(end -1.245616 -1.445768)
			(stroke
				(width 0.1524)
				(type default)
			)
			(layer "F.SilkS")
		)
		(fp_poly
			(pts
				(xy -1.371346 -0.199136) (xy -1.879346 0.054864) (xy -1.879346 -0.453136)
			)
			(stroke
				(width 0)
				(type default)
			)
			(fill yes)
			(layer "F.SilkS")
		)
		(fp_line
			(start 0.724916 -0.925068)
			(end 0.724916 0.925068)
			(stroke
				(width 0.1)
				(type default)
			)
			(layer "F.Fab")
		)
		(fp_line
			(start -0.724916 -0.925068)
			(end 0.724916 -0.925068)
			(stroke
				(width 0.1)
				(type default)
			)
			(layer "F.Fab")
		)
		(fp_line
			(start 0.724916 0.925068)
			(end -0.724916 0.925068)
			(stroke
				(width 0.1)
				(type default)
			)
			(layer "F.Fab")
		)
		(fp_line
			(start -0.724916 0.925068)
			(end -0.724916 -0.925068)
			(stroke
				(width 0.1)
				(type default)
			)
			(layer "F.Fab")
		)
		(fp_poly
			(pts
				(xy -1.894586 -0.453898) (xy -1.894586 0.054102) (xy -1.386586 -0.199898)
			)
			(stroke
				(width 0)
				(type default)
			)
			(fill yes)
			(layer "F.Fab")
		)
		(pad "1" smd circle
			(at -0.649986 -0.199898)
			(size 0 0)
			(layers "F.Cu" "F.Mask" "F.Paste")
			(net "GND")
		)
		(pad "2" smd rect
			(at -0.700024 0.199898 180)
			(size 0.1778 0.8128)
			(layers "F.Cu" "F.Mask" "F.Paste")
			(net "JTAG_BMC_R_D_OE")
		)
		(pad "3" smd rect
			(at -0.40005 0.899922 90)
			(size 0.1778 0.8128)
			(layers "F.Cu" "F.Mask" "F.Paste")
			(net "GND")
		)
		(pad "4" smd rect
			(at 0 0.899922 90)
			(size 0.1778 0.8128)
			(layers "F.Cu" "F.Mask" "F.Paste")
			(net "JTAG_TDO_R1")
		)
		(pad "5" smd rect
			(at 0.40005 0.899922 90)
			(size 0.1778 0.8128)
			(layers "F.Cu" "F.Mask" "F.Paste")
			(net "JTAG_TDI_R")
		)
		(pad "6" smd rect
			(at 0.700024 0.199898)
			(size 0.1778 0.8128)
			(layers "F.Cu" "F.Mask" "F.Paste")
			(net "PVDD18_S5_P0")
		)
		(pad "7" smd rect
			(at 0.700024 -0.199898)
			(size 0.1778 0.8128)
			(layers "F.Cu" "F.Mask" "F.Paste")
			(net "PVDD18_S5_P0")
		)
		(pad "8" smd rect
			(at 0.40005 -0.899922 90)
			(size 0.1778 0.8128)
			(layers "F.Cu" "F.Mask" "F.Paste")
			(net "HDT_HDR_TDI")
		)
		(pad "9" smd rect
			(at 0 -0.899922 90)
			(size 0.1778 0.8128)
			(layers "F.Cu" "F.Mask" "F.Paste")
			(net "HDT_HDR_TDO_R")
		)
		(pad "10" smd rect
			(at -0.40005 -0.912622 90)
			(size 0.1778 0.7874)
			(layers "F.Cu" "F.Mask" "F.Paste")
			(net "PVDD18_S5_P0")
		)
	)
	(footprint ""
		(layer "F.Cu")
		(at 428.813722 -423.621708 90)
		(property "Reference" "R6251"
			(at 0 0 90)
			(layer "F.SilkS")
			(hide yes)
			(effects
				(font
					(size 1.27 1.27)
				)
			)
		)
		(property "Value" ""
			(at 0 0 90)
			(layer "F.Fab")
			(effects
				(font
					(size 1.27 1.27)
				)
			)
		)
		(duplicate_pad_numbers_are_jumpers no)
		(fp_line
			(start 0.7874 -0.4064)
			(end 0.7874 0.4064)
			(stroke
				(width 0.1524)
				(type default)
			)
			(layer "F.SilkS")
		)
		(fp_line
			(start -0.7874 -0.4064)
			(end 0.7874 -0.4064)
			(stroke
				(width 0.1524)
				(type default)
			)
			(layer "F.SilkS")
		)
		(fp_line
			(start 0.7874 0.4064)
			(end -0.7874 0.4064)
			(stroke
				(width 0.1524)
				(type default)
			)
			(layer "F.SilkS")
		)
		(fp_line
			(start -0.7874 0.4064)
			(end -0.7874 -0.4064)
			(stroke
				(width 0.1524)
				(type default)
			)
			(layer "F.SilkS")
		)
		(fp_line
			(start -0.12065 -0.305054)
			(end -0.12065 -0.2794)
			(stroke
				(width 0.1)
				(type default)
			)
			(layer "F.Fab")
		)
		(fp_line
			(start -0.67945 -0.305054)
			(end -0.12065 -0.305054)
			(stroke
				(width 0.1)
				(type default)
			)
			(layer "F.Fab")
		)
		(fp_line
			(start 0.67945 -0.3048)
			(end 0.67945 0.3048)
			(stroke
				(width 0.1)
				(type default)
			)
			(layer "F.Fab")
		)
		(fp_line
			(start 0.12065 -0.3048)
			(end 0.67945 -0.3048)
			(stroke
				(width 0.1)
				(type default)
			)
			(layer "F.Fab")
		)
		(fp_line
			(start 0.12065 -0.2794)
			(end 0.12065 -0.3048)
			(stroke
				(width 0.1)
				(type default)
			)
			(layer "F.Fab")
		)
		(fp_line
			(start -0.12065 -0.2794)
			(end 0.12065 -0.2794)
			(stroke
				(width 0.1)
				(type default)
			)
			(layer "F.Fab")
		)
		(fp_line
			(start 0.120396 0.2794)
			(end -0.12065 0.2794)
			(stroke
				(width 0.1)
				(type default)
			)
			(layer "F.Fab")
		)
		(fp_line
			(start -0.12065 0.2794)
			(end -0.12065 0.3048)
			(stroke
				(width 0.1)
				(type default)
			)
			(layer "F.Fab")
		)
		(fp_line
			(start 0.67945 0.3048)
			(end 0.120396 0.3048)
			(stroke
				(width 0.1)
				(type default)
			)
			(layer "F.Fab")
		)
		(fp_line
			(start 0.120396 0.3048)
			(end 0.120396 0.2794)
			(stroke
				(width 0.1)
				(type default)
			)
			(layer "F.Fab")
		)
		(fp_line
			(start -0.12065 0.3048)
			(end -0.67945 0.3048)
			(stroke
				(width 0.1)
				(type default)
			)
			(layer "F.Fab")
		)
		(fp_line
			(start -0.67945 0.3048)
			(end -0.67945 -0.305054)
			(stroke
				(width 0.1)
				(type default)
			)
			(layer "F.Fab")
		)
		(pad "1" smd circle
			(at -0.40005 0 90)
			(size 0 0)
			(layers "F.Cu" "F.Mask" "F.Paste")
			(net "GND")
		)
		(pad "2" smd circle
			(at 0.40005 0 90)
			(size 0 0)
			(layers "F.Cu" "F.Mask" "F.Paste")
			(net "HSC_TYPE_ADC_A0")
		)
	)
	(footprint ""
		(layer "F.Cu")
		(at 271.093184 -116.321586)
		(property "Reference" "R3731"
			(at 0 0 0)
			(layer "F.SilkS")
			(hide yes)
			(effects
				(font
					(size 1.27 1.27)
				)
			)
		)
		(property "Value" ""
			(at 0 0 0)
			(layer "F.Fab")
			(effects
				(font
					(size 1.27 1.27)
				)
			)
		)
		(duplicate_pad_numbers_are_jumpers no)
		(fp_line
			(start -0.7874 -0.4064)
			(end 0.7874 -0.4064)
			(stroke
				(width 0.1524)
				(type default)
			)
			(layer "F.SilkS")
		)
		(fp_line
			(start -0.7874 0.4064)
			(end -0.7874 -0.4064)
			(stroke
				(width 0.1524)
				(type default)
			)
			(layer "F.SilkS")
		)
		(fp_line
			(start 0.7874 -0.4064)
			(end 0.7874 0.4064)
			(stroke
				(width 0.1524)
				(type default)
			)
			(layer "F.SilkS")
		)
		(fp_line
			(start 0.7874 0.4064)
			(end -0.7874 0.4064)
			(stroke
				(width 0.1524)
				(type default)
			)
			(layer "F.SilkS")
		)
		(fp_line
			(start -0.67945 -0.305054)
			(end -0.12065 -0.305054)
			(stroke
				(width 0.1)
				(type default)
			)
			(layer "F.Fab")
		)
		(fp_line
			(start -0.67945 0.3048)
			(end -0.67945 -0.305054)
			(stroke
				(width 0.1)
				(type default)
			)
			(layer "F.Fab")
		)
		(fp_line
			(start -0.12065 -0.305054)
			(end -0.12065 -0.2794)
			(stroke
				(width 0.1)
				(type default)
			)
			(layer "F.Fab")
		)
		(fp_line
			(start -0.12065 -0.2794)
			(end 0.12065 -0.2794)
			(stroke
				(width 0.1)
				(type default)
			)
			(layer "F.Fab")
		)
		(fp_line
			(start -0.12065 0.2794)
			(end -0.12065 0.3048)
			(stroke
				(width 0.1)
				(type default)
			)
			(layer "F.Fab")
		)
		(fp_line
			(start -0.12065 0.3048)
			(end -0.67945 0.3048)
			(stroke
				(width 0.1)
				(type default)
			)
			(layer "F.Fab")
		)
		(fp_line
			(start 0.120396 0.2794)
			(end -0.12065 0.2794)
			(stroke
				(width 0.1)
				(type default)
			)
			(layer "F.Fab")
		)
		(fp_line
			(start 0.120396 0.3048)
			(end 0.120396 0.2794)
			(stroke
				(width 0.1)
				(type default)
			)
			(layer "F.Fab")
		)
		(fp_line
			(start 0.12065 -0.3048)
			(end 0.67945 -0.3048)
			(stroke
				(width 0.1)
				(type default)
			)
			(layer "F.Fab")
		)
		(fp_line
			(start 0.12065 -0.2794)
			(end 0.12065 -0.3048)
			(stroke
				(width 0.1)
				(type default)
			)
			(layer "F.Fab")
		)
		(fp_line
			(start 0.67945 -0.3048)
			(end 0.67945 0.3048)
			(stroke
				(width 0.1)
				(type default)
			)
			(layer "F.Fab")
		)
		(fp_line
			(start 0.67945 0.3048)
			(end 0.120396 0.3048)
			(stroke
				(width 0.1)
				(type default)
			)
			(layer "F.Fab")
		)
		(pad "1" smd circle
			(at -0.40005 0)
			(size 0 0)
			(layers "F.Cu" "F.Mask" "F.Paste")
			(net "P3V3_AUX")
		)
		(pad "2" smd circle
			(at 0.40005 0)
			(size 0 0)
			(layers "F.Cu" "F.Mask" "F.Paste")
			(net "SMB_LM75_3_3V3AUX_SCL")
		)
	)
	(footprint ""
		(layer "F.Cu")
		(at 118.718584 -62.932056)
		(property "Reference" "R1747"
			(at 0 0 0)
			(layer "F.SilkS")
			(hide yes)
			(effects
				(font
					(size 1.27 1.27)
				)
			)
		)
		(property "Value" ""
			(at 0 0 0)
			(layer "F.Fab")
			(effects
				(font
					(size 1.27 1.27)
				)
			)
		)
		(duplicate_pad_numbers_are_jumpers no)
		(fp_line
			(start -0.7874 -0.4064)
			(end 0.7874 -0.4064)
			(stroke
				(width 0.1524)
				(type default)
			)
			(layer "F.SilkS")
		)
		(fp_line
			(start -0.7874 0.4064)
			(end -0.7874 -0.4064)
			(stroke
				(width 0.1524)
				(type default)
			)
			(layer "F.SilkS")
		)
		(fp_line
			(start 0.7874 -0.4064)
			(end 0.7874 0.4064)
			(stroke
				(width 0.1524)
				(type default)
			)
			(layer "F.SilkS")
		)
		(fp_line
			(start 0.7874 0.4064)
			(end -0.7874 0.4064)
			(stroke
				(width 0.1524)
				(type default)
			)
			(layer "F.SilkS")
		)
		(fp_line
			(start -0.67945 -0.305054)
			(end -0.12065 -0.305054)
			(stroke
				(width 0.1)
				(type default)
			)
			(layer "F.Fab")
		)
		(fp_line
			(start -0.67945 0.3048)
			(end -0.67945 -0.305054)
			(stroke
				(width 0.1)
				(type default)
			)
			(layer "F.Fab")
		)
		(fp_line
			(start -0.12065 -0.305054)
			(end -0.12065 -0.2794)
			(stroke
				(width 0.1)
				(type default)
			)
			(layer "F.Fab")
		)
		(fp_line
			(start -0.12065 -0.2794)
			(end 0.12065 -0.2794)
			(stroke
				(width 0.1)
				(type default)
			)
			(layer "F.Fab")
		)
		(fp_line
			(start -0.12065 0.2794)
			(end -0.12065 0.3048)
			(stroke
				(width 0.1)
				(type default)
			)
			(layer "F.Fab")
		)
		(fp_line
			(start -0.12065 0.3048)
			(end -0.67945 0.3048)
			(stroke
				(width 0.1)
				(type default)
			)
			(layer "F.Fab")
		)
		(fp_line
			(start 0.120396 0.2794)
			(end -0.12065 0.2794)
			(stroke
				(width 0.1)
				(type default)
			)
			(layer "F.Fab")
		)
		(fp_line
			(start 0.120396 0.3048)
			(end 0.120396 0.2794)
			(stroke
				(width 0.1)
				(type default)
			)
			(layer "F.Fab")
		)
		(fp_line
			(start 0.12065 -0.3048)
			(end 0.67945 -0.3048)
			(stroke
				(width 0.1)
				(type default)
			)
			(layer "F.Fab")
		)
		(fp_line
			(start 0.12065 -0.2794)
			(end 0.12065 -0.3048)
			(stroke
				(width 0.1)
				(type default)
			)
			(layer "F.Fab")
		)
		(fp_line
			(start 0.67945 -0.3048)
			(end 0.67945 0.3048)
			(stroke
				(width 0.1)
				(type default)
			)
			(layer "F.Fab")
		)
		(fp_line
			(start 0.67945 0.3048)
			(end 0.120396 0.3048)
			(stroke
				(width 0.1)
				(type default)
			)
			(layer "F.Fab")
		)
		(pad "1" smd circle
			(at -0.40005 0)
			(size 0 0)
			(layers "F.Cu" "F.Mask" "F.Paste")
			(net "P3V3_AUX")
		)
		(pad "2" smd circle
			(at 0.40005 0)
			(size 0 0)
			(layers "F.Cu" "F.Mask" "F.Paste")
			(net "JTAG_SCM_MUX_TCK")
		)
	)
	(footprint ""
		(layer "F.Cu")
		(at 283.464 -423.418 90)
		(property "Reference" "R4492"
			(at 0 0 90)
			(layer "F.SilkS")
			(hide yes)
			(effects
				(font
					(size 1.27 1.27)
				)
			)
		)
		(property "Value" ""
			(at 0 0 90)
			(layer "F.Fab")
			(effects
				(font
					(size 1.27 1.27)
				)
			)
		)
		(duplicate_pad_numbers_are_jumpers no)
		(fp_line
			(start 0.7874 -0.4064)
			(end 0.7874 0.4064)
			(stroke
				(width 0.1524)
				(type default)
			)
			(layer "F.SilkS")
		)
		(fp_line
			(start -0.7874 -0.4064)
			(end 0.7874 -0.4064)
			(stroke
				(width 0.1524)
				(type default)
			)
			(layer "F.SilkS")
		)
		(fp_line
			(start 0.7874 0.4064)
			(end -0.7874 0.4064)
			(stroke
				(width 0.1524)
				(type default)
			)
			(layer "F.SilkS")
		)
		(fp_line
			(start -0.7874 0.4064)
			(end -0.7874 -0.4064)
			(stroke
				(width 0.1524)
				(type default)
			)
			(layer "F.SilkS")
		)
		(fp_line
			(start -0.12065 -0.305054)
			(end -0.12065 -0.2794)
			(stroke
				(width 0.1)
				(type default)
			)
			(layer "F.Fab")
		)
		(fp_line
			(start -0.67945 -0.305054)
			(end -0.12065 -0.305054)
			(stroke
				(width 0.1)
				(type default)
			)
			(layer "F.Fab")
		)
		(fp_line
			(start 0.67945 -0.3048)
			(end 0.67945 0.3048)
			(stroke
				(width 0.1)
				(type default)
			)
			(layer "F.Fab")
		)
		(fp_line
			(start 0.12065 -0.3048)
			(end 0.67945 -0.3048)
			(stroke
				(width 0.1)
				(type default)
			)
			(layer "F.Fab")
		)
		(fp_line
			(start 0.12065 -0.2794)
			(end 0.12065 -0.3048)
			(stroke
				(width 0.1)
				(type default)
			)
			(layer "F.Fab")
		)
		(fp_line
			(start -0.12065 -0.2794)
			(end 0.12065 -0.2794)
			(stroke
				(width 0.1)
				(type default)
			)
			(layer "F.Fab")
		)
		(fp_line
			(start 0.120396 0.2794)
			(end -0.12065 0.2794)
			(stroke
				(width 0.1)
				(type default)
			)
			(layer "F.Fab")
		)
		(fp_line
			(start -0.12065 0.2794)
			(end -0.12065 0.3048)
			(stroke
				(width 0.1)
				(type default)
			)
			(layer "F.Fab")
		)
		(fp_line
			(start 0.67945 0.3048)
			(end 0.120396 0.3048)
			(stroke
				(width 0.1)
				(type default)
			)
			(layer "F.Fab")
		)
		(fp_line
			(start 0.120396 0.3048)
			(end 0.120396 0.2794)
			(stroke
				(width 0.1)
				(type default)
			)
			(layer "F.Fab")
		)
		(fp_line
			(start -0.12065 0.3048)
			(end -0.67945 0.3048)
			(stroke
				(width 0.1)
				(type default)
			)
			(layer "F.Fab")
		)
		(fp_line
			(start -0.67945 0.3048)
			(end -0.67945 -0.305054)
			(stroke
				(width 0.1)
				(type default)
			)
			(layer "F.Fab")
		)
		(pad "1" smd circle
			(at -0.40005 0 90)
			(size 0 0)
			(layers "F.Cu" "F.Mask" "F.Paste")
			(net "CLK_9ZXL045_P0_HIBW")
		)
		(pad "2" smd circle
			(at 0.40005 0 90)
			(size 0 0)
			(layers "F.Cu" "F.Mask" "F.Paste")
			(net "GND")
		)
	)
)
